(kicad_pcb
	(version 20260206)
	(generator "pcbnew")
	(generator_version "10.0")
	(general
		(thickness 1.6)
		(legacy_teardrops no)
	)
	(paper "A4")
	(title_block
		(title "Wiwynn_Tioga_Pass_MB.brd")
		(comment 1 "Tioga Pass / footprints 1874-1881 of 4770")
	)
	(layers
		(0 "F.Cu" signal "TOP")
		(4 "In1.Cu" signal "L2GND")
		(6 "In2.Cu" signal "L3")
		(8 "In3.Cu" signal "L4GND")
		(10 "In4.Cu" signal "L5")
		(12 "In5.Cu" signal "L6GND")
		(14 "In6.Cu" signal "L7VCC")
		(16 "In7.Cu" signal "L8VCC")
		(18 "In8.Cu" signal "L9GND")
		(20 "In9.Cu" signal "L10")
		(22 "In10.Cu" signal "L11GND")
		(24 "In11.Cu" signal "L12")
		(26 "In12.Cu" signal "L13GND")
		(2 "B.Cu" signal "BOTTOM")
		(9 "F.Adhes" user "F.Adhesive")
		(11 "B.Adhes" user "B.Adhesive")
		(13 "F.Paste" user "Package Geometry/Pastemask Top")
		(15 "B.Paste" user "Package Geometry/Pastemask Bottom")
		(5 "F.SilkS" user "Ref Des/Silkscreen Top")
		(7 "B.SilkS" user "Ref Des/Silkscreen Bottom")
		(1 "F.Mask" user "Board Geometry/Soldermask Top")
		(3 "B.Mask" user "Board Geometry/Soldermask Bottom")
		(17 "Dwgs.User" user "User.Drawings")
		(19 "Cmts.User" user "User.Comments")
		(21 "Eco1.User" user "User.Eco1")
		(23 "Eco2.User" user "User.Eco2")
		(25 "Edge.Cuts" user "Board Geometry/Outline")
		(27 "Margin" user)
		(31 "F.CrtYd" user "Package Geometry/Place Bound Top")
		(29 "B.CrtYd" user "Package Geometry/Place Bound Bottom")
		(35 "F.Fab" user "Ref Des/Assembly Top")
		(33 "B.Fab" user "Ref Des/Assembly Bottom")
	)
	(footprint ""
		(layer "F.Cu")
		(at 362.276644 -10.916158)
		(property "Reference" "C7G5"
			(at 0 0 0)
			(layer "F.SilkS")
			(hide yes)
			(effects
				(font
					(size 1.27 1.27)
				)
			)
		)
		(property "Value" ""
			(at 0 0 0)
			(layer "F.Fab")
			(effects
				(font
					(size 1.27 1.27)
				)
			)
		)
		(duplicate_pad_numbers_are_jumpers no)
		(fp_rect
			(start -0.3048 0.9906)
			(end 0.3048 -0.1016)
			(stroke
				(width 0)
				(type default)
			)
			(fill no)
			(layer "F.CrtYd")
		)
		(fp_line
			(start -0.3048 -0.1016)
			(end -0.3048 0.9906)
			(stroke
				(width 0.1)
				(type default)
			)
			(layer "F.Fab")
		)
		(fp_line
			(start -0.3048 0.9906)
			(end 0.3048 0.9906)
			(stroke
				(width 0.1)
				(type default)
			)
			(layer "F.Fab")
		)
		(fp_line
			(start 0.3048 -0.1016)
			(end -0.3048 -0.1016)
			(stroke
				(width 0.1)
				(type default)
			)
			(layer "F.Fab")
		)
		(fp_line
			(start 0.3048 0.9906)
			(end 0.3048 -0.1016)
			(stroke
				(width 0.1)
				(type default)
			)
			(layer "F.Fab")
		)
		(pad "1" smd rect
			(at 0 0)
			(size 0.508 0.508)
			(layers "F.Cu" "F.Mask" "F.Paste")
			(net "P3E_CPU0_PE2_SS_TXP<15>")
		)
		(pad "2" smd rect
			(at 0 0.889)
			(size 0.508 0.508)
			(layers "F.Cu" "F.Mask" "F.Paste")
			(net "P3E_CPU0_PE2_SS_C_TXP<15>")
		)
		(zone
			(layer "F.Cu")
			(hatch none 0.5)
			(connect_pads
				(clearance 0)
			)
			(min_thickness 0.25)
			(keepout
				(tracks not_allowed)
				(vias allowed)
				(pads allowed)
				(copperpour not_allowed)
				(footprints allowed)
			)
			(placement
				(enabled no)
				(sheetname "")
			)
			(fill
				(thermal_gap 0.5)
				(thermal_bridge_width 0.5)
				(island_removal_mode 0)
			)
			(polygon
				(pts
					(xy 362.022644 -10.281158) (xy 362.530644 -10.281158) (xy 362.530644 -10.662158) (xy 362.022644 -10.662158)
				)
			)
		)
		(zone
			(layer "F.Cu")
			(hatch none 0.5)
			(connect_pads
				(clearance 0)
			)
			(min_thickness 0.25)
			(keepout
				(tracks allowed)
				(vias not_allowed)
				(pads allowed)
				(copperpour not_allowed)
				(footprints allowed)
			)
			(placement
				(enabled no)
				(sheetname "")
			)
			(fill
				(thermal_gap 0.5)
				(thermal_bridge_width 0.5)
				(island_removal_mode 0)
			)
			(polygon
				(pts
					(xy 362.022644 -10.281158) (xy 362.530644 -10.281158) (xy 362.530644 -10.662158) (xy 362.022644 -10.662158)
				)
			)
		)
	)
	(footprint ""
		(layer "F.Cu")
		(at 94.50324 -81.573116)
		(property "Reference" "C2D10"
			(at 0 0 0)
			(layer "F.SilkS")
			(hide yes)
			(effects
				(font
					(size 1.27 1.27)
				)
			)
		)
		(property "Value" ""
			(at 0 0 0)
			(layer "F.Fab")
			(effects
				(font
					(size 1.27 1.27)
				)
			)
		)
		(duplicate_pad_numbers_are_jumpers no)
		(fp_poly
			(pts
				(xy -0.4953 -0.2032) (xy 0.4953 -0.2032) (xy 0.4953 1.6002) (xy -0.4953 1.6002)
			)
			(stroke
				(width 0)
				(type default)
			)
			(fill no)
			(layer "F.CrtYd")
		)
		(fp_line
			(start -0.4953 -0.2032)
			(end 0.4953 -0.2032)
			(stroke
				(width 0.1)
				(type default)
			)
			(layer "F.Fab")
		)
		(fp_line
			(start -0.4953 1.6002)
			(end -0.4953 -0.2032)
			(stroke
				(width 0.1)
				(type default)
			)
			(layer "F.Fab")
		)
		(fp_line
			(start 0.4953 -0.2032)
			(end 0.4953 1.6002)
			(stroke
				(width 0.1)
				(type default)
			)
			(layer "F.Fab")
		)
		(fp_line
			(start 0.4953 1.6002)
			(end -0.4953 1.6002)
			(stroke
				(width 0.1)
				(type default)
			)
			(layer "F.Fab")
		)
		(pad "1" smd rect
			(at 0 0)
			(size 0.762 0.889)
			(layers "F.Cu" "F.Mask" "F.Paste")
			(net "PVSA_CPU1")
		)
		(pad "2" smd rect
			(at 0 1.397)
			(size 0.762 0.889)
			(layers "F.Cu" "F.Mask" "F.Paste")
			(net "GND")
		)
		(zone
			(layer "F.Cu")
			(hatch none 0.5)
			(connect_pads
				(clearance 0)
			)
			(min_thickness 0.25)
			(keepout
				(tracks not_allowed)
				(vias allowed)
				(pads allowed)
				(copperpour not_allowed)
				(footprints allowed)
			)
			(placement
				(enabled no)
				(sheetname "")
			)
			(fill
				(thermal_gap 0.5)
				(thermal_bridge_width 0.5)
				(island_removal_mode 0)
			)
			(polygon
				(pts
					(xy 94.12224 -81.128616) (xy 94.88424 -81.128616) (xy 94.88424 -80.620616) (xy 94.12224 -80.620616)
				)
			)
		)
	)
	(footprint ""
		(layer "F.Cu")
		(at 192.786 -3.7465)
		(property "Reference" "R4G20"
			(at 0 0 0)
			(layer "F.SilkS")
			(hide yes)
			(effects
				(font
					(size 1.27 1.27)
				)
			)
		)
		(property "Value" ""
			(at 0 0 0)
			(layer "F.Fab")
			(effects
				(font
					(size 1.27 1.27)
				)
			)
		)
		(duplicate_pad_numbers_are_jumpers no)
		(fp_poly
			(pts
				(xy -0.2794 -0.1016) (xy 0.2794 -0.1016) (xy 0.2794 0.9906) (xy -0.2794 0.9906)
			)
			(stroke
				(width 0)
				(type default)
			)
			(fill no)
			(layer "F.CrtYd")
		)
		(fp_line
			(start -0.2794 -0.1016)
			(end -0.2794 0.9906)
			(stroke
				(width 0.1)
				(type default)
			)
			(layer "F.Fab")
		)
		(fp_line
			(start -0.2794 0.9906)
			(end 0.2794 0.9906)
			(stroke
				(width 0.1)
				(type default)
			)
			(layer "F.Fab")
		)
		(fp_line
			(start 0.2794 -0.1016)
			(end -0.2794 -0.1016)
			(stroke
				(width 0.1)
				(type default)
			)
			(layer "F.Fab")
		)
		(fp_line
			(start 0.2794 0.9906)
			(end 0.2794 -0.1016)
			(stroke
				(width 0.1)
				(type default)
			)
			(layer "F.Fab")
		)
		(pad "1" smd rect
			(at 0 0)
			(size 0.508 0.508)
			(layers "F.Cu" "F.Mask" "F.Paste")
			(net "M_C_CPU_VREF")
		)
		(pad "2" smd rect
			(at 0 0.889)
			(size 0.508 0.508)
			(layers "F.Cu" "F.Mask" "F.Paste")
			(net "M_C_VREF")
		)
		(zone
			(layer "F.Cu")
			(hatch none 0.5)
			(connect_pads
				(clearance 0)
			)
			(min_thickness 0.25)
			(keepout
				(tracks allowed)
				(vias not_allowed)
				(pads allowed)
				(copperpour not_allowed)
				(footprints allowed)
			)
			(placement
				(enabled no)
				(sheetname "")
			)
			(fill
				(thermal_gap 0.5)
				(thermal_bridge_width 0.5)
				(island_removal_mode 0)
			)
			(polygon
				(pts
					(xy 192.532 -3.4925) (xy 193.04 -3.4925) (xy 193.04 -3.1115) (xy 192.532 -3.1115)
				)
			)
		)
		(zone
			(layer "F.Cu")
			(hatch none 0.5)
			(connect_pads
				(clearance 0)
			)
			(min_thickness 0.25)
			(keepout
				(tracks not_allowed)
				(vias allowed)
				(pads allowed)
				(copperpour not_allowed)
				(footprints allowed)
			)
			(placement
				(enabled no)
				(sheetname "")
			)
			(fill
				(thermal_gap 0.5)
				(thermal_bridge_width 0.5)
				(island_removal_mode 0)
			)
			(polygon
				(pts
					(xy 192.532 -3.1115) (xy 193.04 -3.1115) (xy 193.04 -3.4925) (xy 192.532 -3.4925)
				)
			)
		)
	)
	(footprint ""
		(layer "F.Cu")
		(at 362.09224 -133.08457 180)
		(property "Reference" "R7B5"
			(at 0 0 180)
			(layer "F.SilkS")
			(hide yes)
			(effects
				(font
					(size 1.27 1.27)
				)
			)
		)
		(property "Value" ""
			(at 0 0 180)
			(layer "F.Fab")
			(effects
				(font
					(size 1.27 1.27)
				)
			)
		)
		(duplicate_pad_numbers_are_jumpers no)
		(fp_rect
			(start 0.2794 -0.1016)
			(end -0.2794 0.9906)
			(stroke
				(width 0)
				(type default)
			)
			(fill no)
			(layer "F.CrtYd")
		)
		(fp_line
			(start 0.2794 0.9906)
			(end 0.2794 -0.1016)
			(stroke
				(width 0.1)
				(type default)
			)
			(layer "F.Fab")
		)
		(fp_line
			(start 0.2794 -0.1016)
			(end -0.2794 -0.1016)
			(stroke
				(width 0.1)
				(type default)
			)
			(layer "F.Fab")
		)
		(fp_line
			(start -0.2794 0.9906)
			(end 0.2794 0.9906)
			(stroke
				(width 0.1)
				(type default)
			)
			(layer "F.Fab")
		)
		(fp_line
			(start -0.2794 -0.1016)
			(end -0.2794 0.9906)
			(stroke
				(width 0.1)
				(type default)
			)
			(layer "F.Fab")
		)
		(pad "1" smd rect
			(at 0 0 180)
			(size 0.508 0.508)
			(layers "F.Cu" "F.Mask" "F.Paste")
			(net "P3V3_STBY")
		)
		(pad "2" smd rect
			(at 0 0.889 180)
			(size 0.508 0.508)
			(layers "F.Cu" "F.Mask" "F.Paste")
			(net "PWRGD_PVDDQ_DEF_R")
		)
		(zone
			(layer "F.Cu")
			(hatch none 0.5)
			(connect_pads
				(clearance 0)
			)
			(min_thickness 0.25)
			(keepout
				(tracks allowed)
				(vias not_allowed)
				(pads allowed)
				(copperpour not_allowed)
				(footprints allowed)
			)
			(placement
				(enabled no)
				(sheetname "")
			)
			(fill
				(thermal_gap 0.5)
				(thermal_bridge_width 0.5)
				(island_removal_mode 0)
			)
			(polygon
				(pts
					(xy 361.83824 -133.33857) (xy 362.34624 -133.33857) (xy 362.34624 -133.71957) (xy 361.83824 -133.71957)
				)
			)
		)
		(zone
			(layer "F.Cu")
			(hatch none 0.5)
			(connect_pads
				(clearance 0)
			)
			(min_thickness 0.25)
			(keepout
				(tracks not_allowed)
				(vias allowed)
				(pads allowed)
				(copperpour not_allowed)
				(footprints allowed)
			)
			(placement
				(enabled no)
				(sheetname "")
			)
			(fill
				(thermal_gap 0.5)
				(thermal_bridge_width 0.5)
				(island_removal_mode 0)
			)
			(polygon
				(pts
					(xy 361.83824 -133.33857) (xy 362.34624 -133.33857) (xy 362.34624 -133.71957) (xy 361.83824 -133.71957)
				)
			)
		)
	)
	(footprint ""
		(layer "F.Cu")
		(at 155.1051 -22.7457 90)
		(property "Reference" "C3F4"
			(at 0 0 90)
			(layer "F.SilkS")
			(hide yes)
			(effects
				(font
					(size 1.27 1.27)
				)
			)
		)
		(property "Value" ""
			(at 0 0 90)
			(layer "F.Fab")
			(effects
				(font
					(size 1.27 1.27)
				)
			)
		)
		(duplicate_pad_numbers_are_jumpers no)
		(fp_poly
			(pts
				(xy -0.4953 -0.2032) (xy 0.4953 -0.2032) (xy 0.4953 1.6002) (xy -0.4953 1.6002)
			)
			(stroke
				(width 0)
				(type default)
			)
			(fill no)
			(layer "F.CrtYd")
		)
		(fp_line
			(start 0.4953 -0.2032)
			(end 0.4953 1.6002)
			(stroke
				(width 0.1)
				(type default)
			)
			(layer "F.Fab")
		)
		(fp_line
			(start -0.4953 -0.2032)
			(end 0.4953 -0.2032)
			(stroke
				(width 0.1)
				(type default)
			)
			(layer "F.Fab")
		)
		(fp_line
			(start 0.4953 1.6002)
			(end -0.4953 1.6002)
			(stroke
				(width 0.1)
				(type default)
			)
			(layer "F.Fab")
		)
		(fp_line
			(start -0.4953 1.6002)
			(end -0.4953 -0.2032)
			(stroke
				(width 0.1)
				(type default)
			)
			(layer "F.Fab")
		)
		(pad "1" smd rect
			(at 0 0 90)
			(size 0.762 0.889)
			(layers "F.Cu" "F.Mask" "F.Paste")
			(net "PVPP_GHJ")
		)
		(pad "2" smd rect
			(at 0 1.397 90)
			(size 0.762 0.889)
			(layers "F.Cu" "F.Mask" "F.Paste")
			(net "GND")
		)
		(zone
			(layer "F.Cu")
			(hatch none 0.5)
			(connect_pads
				(clearance 0)
			)
			(min_thickness 0.25)
			(keepout
				(tracks not_allowed)
				(vias allowed)
				(pads allowed)
				(copperpour not_allowed)
				(footprints allowed)
			)
			(placement
				(enabled no)
				(sheetname "")
			)
			(fill
				(thermal_gap 0.5)
				(thermal_bridge_width 0.5)
				(island_removal_mode 0)
			)
			(polygon
				(pts
					(xy 155.5496 -22.3647) (xy 155.5496 -23.1267) (xy 156.0576 -23.1267) (xy 156.0576 -22.3647)
				)
			)
		)
	)
	(footprint ""
		(layer "F.Cu")
		(at 173.736 -63.831978 90)
		(property "Reference" "R4E2"
			(at 0 0 90)
			(layer "F.SilkS")
			(hide yes)
			(effects
				(font
					(size 1.27 1.27)
				)
			)
		)
		(property "Value" ""
			(at 0 0 90)
			(layer "F.Fab")
			(effects
				(font
					(size 1.27 1.27)
				)
			)
		)
		(duplicate_pad_numbers_are_jumpers no)
		(fp_poly
			(pts
				(xy -0.2794 -0.1016) (xy 0.2794 -0.1016) (xy 0.2794 0.9906) (xy -0.2794 0.9906)
			)
			(stroke
				(width 0)
				(type default)
			)
			(fill no)
			(layer "F.CrtYd")
		)
		(fp_line
			(start 0.2794 -0.1016)
			(end -0.2794 -0.1016)
			(stroke
				(width 0.1)
				(type default)
			)
			(layer "F.Fab")
		)
		(fp_line
			(start -0.2794 -0.1016)
			(end -0.2794 0.9906)
			(stroke
				(width 0.1)
				(type default)
			)
			(layer "F.Fab")
		)
		(fp_line
			(start 0.2794 0.9906)
			(end 0.2794 -0.1016)
			(stroke
				(width 0.1)
				(type default)
			)
			(layer "F.Fab")
		)
		(fp_line
			(start -0.2794 0.9906)
			(end 0.2794 0.9906)
			(stroke
				(width 0.1)
				(type default)
			)
			(layer "F.Fab")
		)
		(pad "1" smd rect
			(at 0 0 90)
			(size 0.508 0.508)
			(layers "F.Cu" "F.Mask" "F.Paste")
			(net "VR_PVCCIO_CPU1_XADDR2")
		)
		(pad "2" smd rect
			(at 0 0.889 90)
			(size 0.508 0.508)
			(layers "F.Cu" "F.Mask" "F.Paste")
			(net "GND")
		)
		(zone
			(layer "F.Cu")
			(hatch none 0.5)
			(connect_pads
				(clearance 0)
			)
			(min_thickness 0.25)
			(keepout
				(tracks allowed)
				(vias not_allowed)
				(pads allowed)
				(copperpour not_allowed)
				(footprints allowed)
			)
			(placement
				(enabled no)
				(sheetname "")
			)
			(fill
				(thermal_gap 0.5)
				(thermal_bridge_width 0.5)
				(island_removal_mode 0)
			)
			(polygon
				(pts
					(xy 173.99 -63.577978) (xy 173.99 -64.085978) (xy 174.371 -64.085978) (xy 174.371 -63.577978)
				)
			)
		)
		(zone
			(layer "F.Cu")
			(hatch none 0.5)
			(connect_pads
				(clearance 0)
			)
			(min_thickness 0.25)
			(keepout
				(tracks not_allowed)
				(vias allowed)
				(pads allowed)
				(copperpour not_allowed)
				(footprints allowed)
			)
			(placement
				(enabled no)
				(sheetname "")
			)
			(fill
				(thermal_gap 0.5)
				(thermal_bridge_width 0.5)
				(island_removal_mode 0)
			)
			(polygon
				(pts
					(xy 174.371 -63.577978) (xy 174.371 -64.085978) (xy 173.99 -64.085978) (xy 173.99 -63.577978)
				)
			)
		)
	)
	(footprint ""
		(layer "F.Cu")
		(at 94.308168 -3.321812 90)
		(property "Reference" "C2G16"
			(at 0 0 90)
			(layer "F.SilkS")
			(hide yes)
			(effects
				(font
					(size 1.27 1.27)
				)
			)
		)
		(property "Value" ""
			(at 0 0 90)
			(layer "F.Fab")
			(effects
				(font
					(size 1.27 1.27)
				)
			)
		)
		(duplicate_pad_numbers_are_jumpers no)
		(fp_poly
			(pts
				(xy -0.7239 -0.2159) (xy 0.7239 -0.2159) (xy 0.7239 1.9939) (xy -0.7239 1.9939)
			)
			(stroke
				(width 0)
				(type default)
			)
			(fill no)
			(layer "F.CrtYd")
		)
		(fp_line
			(start 0.7239 -0.2159)
			(end -0.7239 -0.2159)
			(stroke
				(width 0.1)
				(type default)
			)
			(layer "F.Fab")
		)
		(fp_line
			(start -0.7239 -0.2159)
			(end -0.7239 1.9939)
			(stroke
				(width 0.1)
				(type default)
			)
			(layer "F.Fab")
		)
		(fp_line
			(start 0.7239 1.9939)
			(end 0.7239 -0.2159)
			(stroke
				(width 0.1)
				(type default)
			)
			(layer "F.Fab")
		)
		(fp_line
			(start -0.7239 1.9939)
			(end 0.7239 1.9939)
			(stroke
				(width 0.1)
				(type default)
			)
			(layer "F.Fab")
		)
		(pad "1" smd rect
			(at 0 0 90)
			(size 1.27 1.016)
			(layers "F.Cu" "F.Mask" "F.Paste")
			(net "PVDDQ_GHJ")
		)
		(pad "2" smd rect
			(at 0 1.778 90)
			(size 1.27 1.016)
			(layers "F.Cu" "F.Mask" "F.Paste")
			(net "GND")
		)
		(zone
			(layer "F.Cu")
			(hatch none 0.5)
			(connect_pads
				(clearance 0)
			)
			(min_thickness 0.25)
			(keepout
				(tracks not_allowed)
				(vias allowed)
				(pads allowed)
				(copperpour not_allowed)
				(footprints allowed)
			)
			(placement
				(enabled no)
				(sheetname "")
			)
			(fill
				(thermal_gap 0.5)
				(thermal_bridge_width 0.5)
				(island_removal_mode 0)
			)
			(polygon
				(pts
					(xy 94.816168 -2.686812) (xy 94.816168 -3.956812) (xy 95.578168 -3.956812) (xy 95.578168 -2.686812)
				)
			)
		)
	)
	(footprint ""
		(layer "F.Cu")
		(at 0.762 -71.247 90)
		(property "Reference" "U1E1"
			(at 2.0066 -2.13233 90)
			(unlocked yes)
			(layer "F.SilkS")
			(effects
				(font
					(size 0.7874 0.5842)
					(thickness 0.1524)
				)
			)
		)
		(property "Value" ""
			(at 0 0 90)
			(layer "F.Fab")
			(effects
				(font
					(size 1.27 1.27)
				)
			)
		)
		(duplicate_pad_numbers_are_jumpers no)
		(fp_line
			(start 1.566672 -0.52324)
			(end 0.985774 -0.52324)
			(stroke
				(width 0.1524)
				(type default)
			)
			(layer "F.SilkS")
		)
		(fp_line
			(start 1.583436 2.47396)
			(end 0.965454 2.47396)
			(stroke
				(width 0.1524)
				(type default)
			)
			(layer "F.SilkS")
		)
		(fp_circle
			(center -0.635 -0.889)
			(end -0.635 -0.762)
			(stroke
				(width 0.254)
				(type default)
			)
			(fill no)
			(layer "F.SilkS")
		)
		(fp_rect
			(start 0.3937 2.47396)
			(end 2.1463 -0.52324)
			(stroke
				(width 0)
				(type default)
			)
			(fill no)
			(layer "F.CrtYd")
		)
		(fp_line
			(start 2.1463 -0.52324)
			(end 2.1463 2.47396)
			(stroke
				(width 0.1)
				(type default)
			)
			(layer "F.Fab")
		)
		(fp_line
			(start 0.3937 -0.52324)
			(end 2.1463 -0.52324)
			(stroke
				(width 0.1)
				(type default)
			)
			(layer "F.Fab")
		)
		(fp_line
			(start 2.1463 2.47396)
			(end 0.3937 2.47396)
			(stroke
				(width 0.1)
				(type default)
			)
			(layer "F.Fab")
		)
		(fp_line
			(start 0.3937 2.47396)
			(end 0.3937 -0.52324)
			(stroke
				(width 0.1)
				(type default)
			)
			(layer "F.Fab")
		)
		(fp_circle
			(center -0.635 -0.889)
			(end -0.635 -0.762)
			(stroke
				(width 0.254)
				(type default)
			)
			(fill no)
			(layer "F.Fab")
		)
		(pad "1" smd rect
			(at 0 0 90)
			(size 1.27 0.381)
			(layers "F.Cu" "F.Mask" "F.Paste")
			(net "ISENSE_TMP421_2_DXP")
		)
		(pad "2" smd rect
			(at 0 0.65024 90)
			(size 1.27 0.381)
			(layers "F.Cu" "F.Mask" "F.Paste")
			(net "ISENSE_TMP421_2_DXN")
		)
		(pad "3" smd rect
			(at 0 1.30048 90)
			(size 1.27 0.381)
			(layers "F.Cu" "F.Mask" "F.Paste")
			(net "PD_TMP421_2_A1")
		)
		(pad "4" smd rect
			(at 0 1.95072 90)
			(size 1.27 0.381)
			(layers "F.Cu" "F.Mask" "F.Paste")
			(net "PU_TMP421_2_A0")
		)
		(pad "5" smd rect
			(at 2.54 1.95072 90)
			(size 1.27 0.381)
			(layers "F.Cu" "F.Mask" "F.Paste")
			(net "GND")
		)
		(pad "6" smd rect
			(at 2.54 1.30048 90)
			(size 1.27 0.381)
			(layers "F.Cu" "F.Mask" "F.Paste")
			(net "SMB_SENSOR_TMP421_2_SDA")
		)
		(pad "7" smd rect
			(at 2.54 0.65024 90)
			(size 1.27 0.381)
			(layers "F.Cu" "F.Mask" "F.Paste")
			(net "SMB_SENSOR_TMP421_2_SCL")
		)
		(pad "8" smd rect
			(at 2.54 0 90)
			(size 1.27 0.381)
			(layers "F.Cu" "F.Mask" "F.Paste")
			(net "P3V3_STBY")
		)
	)
)
